# S9S_MB_2U (Grand Teton) — schematic netlist excerpt (pin names and nets, part order shuffled) for the footprints in the layout excerpt that follows; sources: Cadence DE-HDL packaged netlist, KiCad conversion of 03242023_DA0F0TMBIJ0_F0T_Motherboard_J_brd_V01_OCP.brd

U236  PCA9617ADP  IC  pkg TSSOP8_3XB  page 238
  VCCA  = P3V3_AUX
  SCLA  = SMB_OCP_SFF_3V3AUX_SCL
  SDAA  = SMB_OCP_SFF_3V3AUX_SDA
  GND  = GND
  EN  = HP_LVC3_OCP_V3_1_R_EN
  SDAB  = SMB_OCP_SFF_3V3AUX_BUF_SDA
  SCLB  = SMB_OCP_SFF_3V3AUX_BUF_SCL
  VCCB  = P3V3_OCP_SFF

C2042  Q_CAP  100PF 50V 5% EMPTY  pkg 0402  page 250 : A = P3V3_AUX_ADC_MAM ; B = GND

(kicad_pcb
	(version 20260206)
	(generator "pcbnew")
	(generator_version "10.0")
	(general
		(thickness 1.6)
		(legacy_teardrops no)
	)
	(paper "A4")
	(title_block
		(title "03242023_DA0F0TMBIJ0_F0T_Motherboard_J_brd_V01_OCP.brd")
		(comment 1 "Grand Teton / footprints 811-812 of 6105")
	)
	(layers
		(0 "F.Cu" signal "TOP")
		(4 "In1.Cu" signal "GND")
		(6 "In2.Cu" signal "IN1")
		(8 "In3.Cu" signal "GND1")
		(10 "In4.Cu" signal "IN2")
		(12 "In5.Cu" signal "GND2")
		(14 "In6.Cu" signal "IN3")
		(16 "In7.Cu" signal "GND3")
		(18 "In8.Cu" signal "VCC")
		(20 "In9.Cu" signal "VCC1")
		(22 "In10.Cu" signal "GND4")
		(24 "In11.Cu" signal "IN4")
		(26 "In12.Cu" signal "GND5")
		(28 "In13.Cu" signal "IN5")
		(30 "In14.Cu" signal "GND6")
		(32 "In15.Cu" signal "IN6")
		(34 "In16.Cu" signal "GND7")
		(2 "B.Cu" signal "BOTTOM")
		(9 "F.Adhes" user "F.Adhesive")
		(11 "B.Adhes" user "B.Adhesive")
		(13 "F.Paste" user "Package Geometry/Pastemask Top")
		(15 "B.Paste" user "Package Geometry/Pastemask Bottom")
		(5 "F.SilkS" user "Ref Des/Silkscreen Top")
		(7 "B.SilkS" user "Ref Des/Silkscreen Bottom")
		(1 "F.Mask" user "Board Geometry/Soldermask Top")
		(3 "B.Mask" user "Board Geometry/Soldermask Bottom")
		(17 "Dwgs.User" user "User.Drawings")
		(19 "Cmts.User" user "User.Comments")
		(21 "Eco1.User" user "User.Eco1")
		(23 "Eco2.User" user "User.Eco2")
		(25 "Edge.Cuts" user "Board Geometry/Outline")
		(27 "Margin" user)
		(31 "F.CrtYd" user "Package Geometry/Place Bound Top")
		(29 "B.CrtYd" user "Package Geometry/Place Bound Bottom")
		(35 "F.Fab" user "Ref Des/Assembly Top")
		(33 "B.Fab" user "Ref Des/Assembly Bottom")
	)
	(footprint ""
		(layer "F.Cu")
		(at 444.87338 -44.670218)
		(property "Reference" "U236"
			(at -3.71348 -2.052828 0)
			(unlocked yes)
			(layer "F.SilkS")
			(effects
				(font
					(size 0.7874 0.5842)
					(thickness 0.1524)
				)
				(justify left)
			)
		)
		(property "Value" ""
			(at 0 0 0)
			(layer "F.Fab")
			(effects
				(font
					(size 1.27 1.27)
				)
			)
		)
		(duplicate_pad_numbers_are_jumpers no)
		(fp_line
			(start -1.463548 -1.549908)
			(end -0.787908 -1.549908)
			(stroke
				(width 0.1524)
				(type default)
			)
			(layer "F.SilkS")
		)
		(fp_line
			(start -1.463548 1.549908)
			(end -1.463548 -1.549908)
			(stroke
				(width 0.1524)
				(type default)
			)
			(layer "F.SilkS")
		)
		(fp_line
			(start -0.787908 -1.549908)
			(end 0 -0.762)
			(stroke
				(width 0.1524)
				(type default)
			)
			(layer "F.SilkS")
		)
		(fp_line
			(start 0 -0.762)
			(end 0.762 -1.549908)
			(stroke
				(width 0.1524)
				(type default)
			)
			(layer "F.SilkS")
		)
		(fp_line
			(start 0.762 -1.549908)
			(end 1.463548 -1.549908)
			(stroke
				(width 0.1524)
				(type default)
			)
			(layer "F.SilkS")
		)
		(fp_line
			(start 1.463548 -1.549908)
			(end 1.463548 1.549908)
			(stroke
				(width 0.1524)
				(type default)
			)
			(layer "F.SilkS")
		)
		(fp_line
			(start 1.463548 1.549908)
			(end -1.463548 1.549908)
			(stroke
				(width 0.1524)
				(type default)
			)
			(layer "F.SilkS")
		)
		(fp_poly
			(pts
				(xy -2.86004 -1.050036) (xy -3.4798 -0.740156) (xy -3.4798 -1.359916)
			)
			(stroke
				(width 0)
				(type default)
			)
			(fill yes)
			(layer "F.SilkS")
		)
		(fp_line
			(start -1.549908 -1.549908)
			(end 1.549908 -1.549908)
			(stroke
				(width 0.1)
				(type default)
			)
			(layer "F.Fab")
		)
		(fp_line
			(start -1.549908 1.549908)
			(end -1.549908 -1.549908)
			(stroke
				(width 0.1)
				(type default)
			)
			(layer "F.Fab")
		)
		(fp_line
			(start 1.549908 -1.549908)
			(end 1.549908 1.549908)
			(stroke
				(width 0.1)
				(type default)
			)
			(layer "F.Fab")
		)
		(fp_line
			(start 1.549908 1.549908)
			(end -1.549908 1.549908)
			(stroke
				(width 0.1)
				(type default)
			)
			(layer "F.Fab")
		)
		(fp_poly
			(pts
				(xy -3.4798 -1.359916) (xy -2.86004 -1.050036) (xy -3.4798 -0.740156)
			)
			(stroke
				(width 0)
				(type default)
			)
			(fill yes)
			(layer "F.Fab")
		)
		(pad "1" smd rect
			(at -2.175002 -1.050036 90)
			(size 0.6096 1.1684)
			(layers "F.Cu" "F.Mask" "F.Paste")
			(net "P3V3_AUX")
		)
		(pad "2" smd rect
			(at -2.175002 -0.32512 90)
			(size 0.4318 1.1684)
			(layers "F.Cu" "F.Mask" "F.Paste")
			(net "SMB_OCP_SFF_3V3AUX_SCL")
		)
		(pad "3" smd rect
			(at -2.175002 0.32512 90)
			(size 0.4318 1.1684)
			(layers "F.Cu" "F.Mask" "F.Paste")
			(net "SMB_OCP_SFF_3V3AUX_SDA")
		)
		(pad "4" smd rect
			(at -2.175002 1.050036 90)
			(size 0.6096 1.1684)
			(layers "F.Cu" "F.Mask" "F.Paste")
			(net "GND")
		)
		(pad "5" smd rect
			(at 2.175002 1.050036 90)
			(size 0.6096 1.1684)
			(layers "F.Cu" "F.Mask" "F.Paste")
			(net "HP_LVC3_OCP_V3_1_R_EN")
		)
		(pad "6" smd rect
			(at 2.175002 0.32512 90)
			(size 0.4318 1.1684)
			(layers "F.Cu" "F.Mask" "F.Paste")
			(net "SMB_OCP_SFF_3V3AUX_BUF_SDA")
		)
		(pad "7" smd rect
			(at 2.175002 -0.32512 90)
			(size 0.4318 1.1684)
			(layers "F.Cu" "F.Mask" "F.Paste")
			(net "SMB_OCP_SFF_3V3AUX_BUF_SCL")
		)
		(pad "8" smd rect
			(at 2.175002 -1.050036 90)
			(size 0.6096 1.1684)
			(layers "F.Cu" "F.Mask" "F.Paste")
			(net "P3V3_OCP_SFF")
		)
	)
	(footprint ""
		(layer "F.Cu")
		(at 46.350428 -98.824034)
		(property "Reference" "C2042"
			(at 0 0 0)
			(layer "F.SilkS")
			(hide yes)
			(effects
				(font
					(size 1.27 1.27)
				)
			)
		)
		(property "Value" ""
			(at 0 0 0)
			(layer "F.Fab")
			(effects
				(font
					(size 1.27 1.27)
				)
			)
		)
		(duplicate_pad_numbers_are_jumpers no)
		(fp_line
			(start -0.7874 -0.4064)
			(end 0.7874 -0.4064)
			(stroke
				(width 0.1524)
				(type default)
			)
			(layer "F.SilkS")
		)
		(fp_line
			(start -0.7874 0.4064)
			(end -0.7874 -0.4064)
			(stroke
				(width 0.1524)
				(type default)
			)
			(layer "F.SilkS")
		)
		(fp_line
			(start 0.7874 -0.4064)
			(end 0.7874 0.4064)
			(stroke
				(width 0.1524)
				(type default)
			)
			(layer "F.SilkS")
		)
		(fp_line
			(start 0.7874 0.4064)
			(end -0.7874 0.4064)
			(stroke
				(width 0.1524)
				(type default)
			)
			(layer "F.SilkS")
		)
		(fp_line
			(start -0.67945 -0.305054)
			(end -0.12065 -0.305054)
			(stroke
				(width 0.1)
				(type default)
			)
			(layer "F.Fab")
		)
		(fp_line
			(start -0.67945 0.3048)
			(end -0.67945 -0.305054)
			(stroke
				(width 0.1)
				(type default)
			)
			(layer "F.Fab")
		)
		(fp_line
			(start -0.12065 -0.305054)
			(end -0.12065 -0.2794)
			(stroke
				(width 0.1)
				(type default)
			)
			(layer "F.Fab")
		)
		(fp_line
			(start -0.12065 -0.2794)
			(end 0.12065 -0.2794)
			(stroke
				(width 0.1)
				(type default)
			)
			(layer "F.Fab")
		)
		(fp_line
			(start -0.12065 0.2794)
			(end -0.12065 0.3048)
			(stroke
				(width 0.1)
				(type default)
			)
			(layer "F.Fab")
		)
		(fp_line
			(start -0.12065 0.3048)
			(end -0.67945 0.3048)
			(stroke
				(width 0.1)
				(type default)
			)
			(layer "F.Fab")
		)
		(fp_line
			(start 0.120396 0.2794)
			(end -0.12065 0.2794)
			(stroke
				(width 0.1)
				(type default)
			)
			(layer "F.Fab")
		)
		(fp_line
			(start 0.120396 0.3048)
			(end 0.120396 0.2794)
			(stroke
				(width 0.1)
				(type default)
			)
			(layer "F.Fab")
		)
		(fp_line
			(start 0.12065 -0.3048)
			(end 0.67945 -0.3048)
			(stroke
				(width 0.1)
				(type default)
			)
			(layer "F.Fab")
		)
		(fp_line
			(start 0.12065 -0.2794)
			(end 0.12065 -0.3048)
			(stroke
				(width 0.1)
				(type default)
			)
			(layer "F.Fab")
		)
		(fp_line
			(start 0.67945 -0.3048)
			(end 0.67945 0.3048)
			(stroke
				(width 0.1)
				(type default)
			)
			(layer "F.Fab")
		)
		(fp_line
			(start 0.67945 0.3048)
			(end 0.120396 0.3048)
			(stroke
				(width 0.1)
				(type default)
			)
			(layer "F.Fab")
		)
		(pad "1" smd circle
			(at -0.40005 0)
			(size 0 0)
			(layers "F.Cu" "F.Mask" "F.Paste")
			(net "P3V3_AUX_ADC_MAM")
		)
		(pad "2" smd circle
			(at 0.40005 0)
			(size 0 0)
			(layers "F.Cu" "F.Mask" "F.Paste")
			(net "GND")
		)
	)
)
